# BASEBOARD_FAB2 (Tioga Pass) — schematic netlist excerpt (pin names and nets, part order shuffled) for the footprints in the layout excerpt that follows; sources: Cadence DE-HDL packaged netlist, KiCad conversion of Wiwynn_Tioga_Pass_MB.brd

R9B5  RES  49.9 1% CHIP  pkg 0402  page 167 : A = ISENSE_TMP421_1_BC ; B = ISENSE_TMP421_1_DXN
CT7  CAP_A  0.1UF 16V 10% X7R  pkg 0402V  page 227 : A = VR_PVDDQ_KLM_AIREF1 ; B = GND
C1A17  CAP_A  0.01UF 25V 10% X7R  pkg 0402V  page 86 : A = M_L_VREF ; B = GND

(kicad_pcb
	(version 20260206)
	(generator "pcbnew")
	(generator_version "10.0")
	(general
		(thickness 1.6)
		(legacy_teardrops no)
	)
	(paper "A4")
	(title_block
		(title "Wiwynn_Tioga_Pass_MB.brd")
		(comment 1 "Tioga Pass / footprints 1296-1298 of 4770")
	)
	(layers
		(0 "F.Cu" signal "TOP")
		(4 "In1.Cu" signal "L2GND")
		(6 "In2.Cu" signal "L3")
		(8 "In3.Cu" signal "L4GND")
		(10 "In4.Cu" signal "L5")
		(12 "In5.Cu" signal "L6GND")
		(14 "In6.Cu" signal "L7VCC")
		(16 "In7.Cu" signal "L8VCC")
		(18 "In8.Cu" signal "L9GND")
		(20 "In9.Cu" signal "L10")
		(22 "In10.Cu" signal "L11GND")
		(24 "In11.Cu" signal "L12")
		(26 "In12.Cu" signal "L13GND")
		(2 "B.Cu" signal "BOTTOM")
		(9 "F.Adhes" user "F.Adhesive")
		(11 "B.Adhes" user "B.Adhesive")
		(13 "F.Paste" user "Package Geometry/Pastemask Top")
		(15 "B.Paste" user "Package Geometry/Pastemask Bottom")
		(5 "F.SilkS" user "Ref Des/Silkscreen Top")
		(7 "B.SilkS" user "Ref Des/Silkscreen Bottom")
		(1 "F.Mask" user "Board Geometry/Soldermask Top")
		(3 "B.Mask" user "Board Geometry/Soldermask Bottom")
		(17 "Dwgs.User" user "User.Drawings")
		(19 "Cmts.User" user "User.Comments")
		(21 "Eco1.User" user "User.Eco1")
		(23 "Eco2.User" user "User.Eco2")
		(25 "Edge.Cuts" user "Board Geometry/Outline")
		(27 "Margin" user)
		(31 "F.CrtYd" user "Package Geometry/Place Bound Top")
		(29 "B.CrtYd" user "Package Geometry/Place Bound Bottom")
		(35 "F.Fab" user "Ref Des/Assembly Top")
		(33 "B.Fab" user "Ref Des/Assembly Bottom")
	)
	(footprint ""
		(layer "F.Cu")
		(at 30.477968 -140.0556 90)
		(property "Reference" "C1A17"
			(at 0 0 90)
			(layer "F.SilkS")
			(hide yes)
			(effects
				(font
					(size 1.27 1.27)
				)
			)
		)
		(property "Value" ""
			(at 0 0 90)
			(layer "F.Fab")
			(effects
				(font
					(size 1.27 1.27)
				)
			)
		)
		(duplicate_pad_numbers_are_jumpers no)
		(fp_poly
			(pts
				(xy 0.3048 -0.1016) (xy 0.3048 0.9906) (xy -0.3048 0.9906) (xy -0.3048 -0.1016)
			)
			(stroke
				(width 0)
				(type default)
			)
			(fill no)
			(layer "F.CrtYd")
		)
		(fp_line
			(start 0.3048 -0.1016)
			(end -0.3048 -0.1016)
			(stroke
				(width 0.1)
				(type default)
			)
			(layer "F.Fab")
		)
		(fp_line
			(start -0.3048 -0.1016)
			(end -0.3048 0.9906)
			(stroke
				(width 0.1)
				(type default)
			)
			(layer "F.Fab")
		)
		(fp_line
			(start 0.3048 0.9906)
			(end 0.3048 -0.1016)
			(stroke
				(width 0.1)
				(type default)
			)
			(layer "F.Fab")
		)
		(fp_line
			(start -0.3048 0.9906)
			(end 0.3048 0.9906)
			(stroke
				(width 0.1)
				(type default)
			)
			(layer "F.Fab")
		)
		(pad "1" smd rect
			(at 0 0 90)
			(size 0.508 0.508)
			(layers "F.Cu" "F.Mask" "F.Paste")
			(net "M_L_VREF")
		)
		(pad "2" smd rect
			(at 0 0.889 90)
			(size 0.508 0.508)
			(layers "F.Cu" "F.Mask" "F.Paste")
			(net "GND")
		)
		(zone
			(layer "F.Cu")
			(hatch none 0.5)
			(connect_pads
				(clearance 0)
			)
			(min_thickness 0.25)
			(keepout
				(tracks allowed)
				(vias not_allowed)
				(pads allowed)
				(copperpour not_allowed)
				(footprints allowed)
			)
			(placement
				(enabled no)
				(sheetname "")
			)
			(fill
				(thermal_gap 0.5)
				(thermal_bridge_width 0.5)
				(island_removal_mode 0)
			)
			(polygon
				(pts
					(xy 30.731968 -139.8016) (xy 30.731968 -140.3096) (xy 31.112968 -140.3096) (xy 31.112968 -139.8016)
				)
			)
		)
		(zone
			(layer "F.Cu")
			(hatch none 0.5)
			(connect_pads
				(clearance 0)
			)
			(min_thickness 0.25)
			(keepout
				(tracks not_allowed)
				(vias allowed)
				(pads allowed)
				(copperpour not_allowed)
				(footprints allowed)
			)
			(placement
				(enabled no)
				(sheetname "")
			)
			(fill
				(thermal_gap 0.5)
				(thermal_bridge_width 0.5)
				(island_removal_mode 0)
			)
			(polygon
				(pts
					(xy 31.112968 -139.8016) (xy 31.112968 -140.3096) (xy 30.731968 -140.3096) (xy 30.731968 -139.8016)
				)
			)
		)
	)
	(footprint ""
		(layer "F.Cu")
		(at 485.87406 -122.91314 90)
		(property "Reference" "R9B5"
			(at 0 0 90)
			(layer "F.SilkS")
			(hide yes)
			(effects
				(font
					(size 1.27 1.27)
				)
			)
		)
		(property "Value" ""
			(at 0 0 90)
			(layer "F.Fab")
			(effects
				(font
					(size 1.27 1.27)
				)
			)
		)
		(duplicate_pad_numbers_are_jumpers no)
		(fp_rect
			(start 0.2794 0.9906)
			(end -0.2794 -0.1016)
			(stroke
				(width 0)
				(type default)
			)
			(fill no)
			(layer "F.CrtYd")
		)
		(fp_line
			(start 0.2794 -0.1016)
			(end -0.2794 -0.1016)
			(stroke
				(width 0.1)
				(type default)
			)
			(layer "F.Fab")
		)
		(fp_line
			(start -0.2794 -0.1016)
			(end -0.2794 0.9906)
			(stroke
				(width 0.1)
				(type default)
			)
			(layer "F.Fab")
		)
		(fp_line
			(start 0.2794 0.9906)
			(end 0.2794 -0.1016)
			(stroke
				(width 0.1)
				(type default)
			)
			(layer "F.Fab")
		)
		(fp_line
			(start -0.2794 0.9906)
			(end 0.2794 0.9906)
			(stroke
				(width 0.1)
				(type default)
			)
			(layer "F.Fab")
		)
		(pad "1" smd rect
			(at 0 0 90)
			(size 0.508 0.508)
			(layers "F.Cu" "F.Mask" "F.Paste")
			(net "ISENSE_TMP421_1_BC")
		)
		(pad "2" smd rect
			(at 0 0.889 90)
			(size 0.508 0.508)
			(layers "F.Cu" "F.Mask" "F.Paste")
			(net "ISENSE_TMP421_1_DXN")
		)
		(zone
			(layer "F.Cu")
			(hatch none 0.5)
			(connect_pads
				(clearance 0)
			)
			(min_thickness 0.25)
			(keepout
				(tracks allowed)
				(vias not_allowed)
				(pads allowed)
				(copperpour not_allowed)
				(footprints allowed)
			)
			(placement
				(enabled no)
				(sheetname "")
			)
			(fill
				(thermal_gap 0.5)
				(thermal_bridge_width 0.5)
				(island_removal_mode 0)
			)
			(polygon
				(pts
					(xy 486.50906 -123.16714) (xy 486.12806 -123.16714) (xy 486.12806 -122.65914) (xy 486.50906 -122.65914)
				)
			)
		)
	)
	(footprint ""
		(layer "F.Cu")
		(at -1.8542 -134.3152 90)
		(property "Reference" "CT7"
			(at -2.79273 1.3716 180)
			(unlocked yes)
			(layer "F.SilkS")
			(effects
				(font
					(size 0.7874 0.5842)
					(thickness 0.1524)
				)
				(justify left)
			)
		)
		(property "Value" ""
			(at 0 0 90)
			(layer "F.Fab")
			(effects
				(font
					(size 1.27 1.27)
				)
			)
		)
		(duplicate_pad_numbers_are_jumpers no)
		(fp_poly
			(pts
				(xy 0.3048 -0.1016) (xy 0.3048 0.9906) (xy -0.3048 0.9906) (xy -0.3048 -0.1016)
			)
			(stroke
				(width 0)
				(type default)
			)
			(fill no)
			(layer "F.CrtYd")
		)
		(fp_line
			(start 0.3048 -0.1016)
			(end -0.3048 -0.1016)
			(stroke
				(width 0.1)
				(type default)
			)
			(layer "F.Fab")
		)
		(fp_line
			(start -0.3048 -0.1016)
			(end -0.3048 0.9906)
			(stroke
				(width 0.1)
				(type default)
			)
			(layer "F.Fab")
		)
		(fp_line
			(start 0.3048 0.9906)
			(end 0.3048 -0.1016)
			(stroke
				(width 0.1)
				(type default)
			)
			(layer "F.Fab")
		)
		(fp_line
			(start -0.3048 0.9906)
			(end 0.3048 0.9906)
			(stroke
				(width 0.1)
				(type default)
			)
			(layer "F.Fab")
		)
		(pad "1" smd rect
			(at 0 0 90)
			(size 0.508 0.508)
			(layers "F.Cu" "F.Mask" "F.Paste")
			(net "VR_PVDDQ_KLM_AIREF1")
		)
		(pad "2" smd rect
			(at 0 0.889 90)
			(size 0.508 0.508)
			(layers "F.Cu" "F.Mask" "F.Paste")
			(net "GND")
		)
		(zone
			(layer "F.Cu")
			(hatch none 0.5)
			(connect_pads
				(clearance 0)
			)
			(min_thickness 0.25)
			(keepout
				(tracks allowed)
				(vias not_allowed)
				(pads allowed)
				(copperpour not_allowed)
				(footprints allowed)
			)
			(placement
				(enabled no)
				(sheetname "")
			)
			(fill
				(thermal_gap 0.5)
				(thermal_bridge_width 0.5)
				(island_removal_mode 0)
			)
			(polygon
				(pts
					(xy -1.6002 -134.0612) (xy -1.6002 -134.5692) (xy -1.2192 -134.5692) (xy -1.2192 -134.0612)
				)
			)
		)
		(zone
			(layer "F.Cu")
			(hatch none 0.5)
			(connect_pads
				(clearance 0)
			)
			(min_thickness 0.25)
			(keepout
				(tracks not_allowed)
				(vias allowed)
				(pads allowed)
				(copperpour not_allowed)
				(footprints allowed)
			)
			(placement
				(enabled no)
				(sheetname "")
			)
			(fill
				(thermal_gap 0.5)
				(thermal_bridge_width 0.5)
				(island_removal_mode 0)
			)
			(polygon
				(pts
					(xy -1.2192 -134.0612) (xy -1.2192 -134.5692) (xy -1.6002 -134.5692) (xy -1.6002 -134.0612)
				)
			)
		)
	)
)
